# S9S_MB_2U (Grand Teton) — schematic netlist excerpt (pin names and nets, part order shuffled) for the footprints in the layout excerpt that follows; sources: Cadence DE-HDL packaged netlist, KiCad conversion of 03242023_DA0F0TMBIJ0_F0T_Motherboard_J_brd_V01_OCP.brd

C277  Q_CAP  22UF 4V 20% X6S  pkg C0402  page 77 : A = PVCCIN_CPU1 ; B = GND
R4200  Q_RES  1K 1% EMPTY  pkg 0402LF  page 170 : A = P3V3_AUX ; B = U273_3_ADD0

(kicad_pcb
	(version 20260206)
	(generator "pcbnew")
	(generator_version "10.0")
	(general
		(thickness 1.6)
		(legacy_teardrops no)
	)
	(paper "A4")
	(title_block
		(title "03242023_DA0F0TMBIJ0_F0T_Motherboard_J_brd_V01_OCP.brd")
		(comment 1 "Grand Teton / footprints 2151-2152 of 6105")
	)
	(layers
		(0 "F.Cu" signal "TOP")
		(4 "In1.Cu" signal "GND")
		(6 "In2.Cu" signal "IN1")
		(8 "In3.Cu" signal "GND1")
		(10 "In4.Cu" signal "IN2")
		(12 "In5.Cu" signal "GND2")
		(14 "In6.Cu" signal "IN3")
		(16 "In7.Cu" signal "GND3")
		(18 "In8.Cu" signal "VCC")
		(20 "In9.Cu" signal "VCC1")
		(22 "In10.Cu" signal "GND4")
		(24 "In11.Cu" signal "IN4")
		(26 "In12.Cu" signal "GND5")
		(28 "In13.Cu" signal "IN5")
		(30 "In14.Cu" signal "GND6")
		(32 "In15.Cu" signal "IN6")
		(34 "In16.Cu" signal "GND7")
		(2 "B.Cu" signal "BOTTOM")
		(9 "F.Adhes" user "F.Adhesive")
		(11 "B.Adhes" user "B.Adhesive")
		(13 "F.Paste" user "Package Geometry/Pastemask Top")
		(15 "B.Paste" user "Package Geometry/Pastemask Bottom")
		(5 "F.SilkS" user "Ref Des/Silkscreen Top")
		(7 "B.SilkS" user "Ref Des/Silkscreen Bottom")
		(1 "F.Mask" user "Board Geometry/Soldermask Top")
		(3 "B.Mask" user "Board Geometry/Soldermask Bottom")
		(17 "Dwgs.User" user "User.Drawings")
		(19 "Cmts.User" user "User.Comments")
		(21 "Eco1.User" user "User.Eco1")
		(23 "Eco2.User" user "User.Eco2")
		(25 "Edge.Cuts" user "Board Geometry/Outline")
		(27 "Margin" user)
		(31 "F.CrtYd" user "Package Geometry/Place Bound Top")
		(29 "B.CrtYd" user "Package Geometry/Place Bound Bottom")
		(35 "F.Fab" user "Ref Des/Assembly Top")
		(33 "B.Fab" user "Ref Des/Assembly Bottom")
	)
	(footprint ""
		(layer "F.Cu")
		(at 116.561616 -252.956568 -90)
		(property "Reference" "C277"
			(at 0 0 270)
			(layer "F.SilkS")
			(hide yes)
			(effects
				(font
					(size 1.27 1.27)
				)
			)
		)
		(property "Value" ""
			(at 0 0 270)
			(layer "F.Fab")
			(effects
				(font
					(size 1.27 1.27)
				)
			)
		)
		(duplicate_pad_numbers_are_jumpers no)
		(fp_line
			(start -0.7874 0.4064)
			(end -0.7874 -0.4064)
			(stroke
				(width 0.1524)
				(type default)
			)
			(layer "F.SilkS")
		)
		(fp_line
			(start 0.7874 0.4064)
			(end -0.7874 0.4064)
			(stroke
				(width 0.1524)
				(type default)
			)
			(layer "F.SilkS")
		)
		(fp_line
			(start -0.7874 -0.4064)
			(end 0.7874 -0.4064)
			(stroke
				(width 0.1524)
				(type default)
			)
			(layer "F.SilkS")
		)
		(fp_line
			(start 0.7874 -0.4064)
			(end 0.7874 0.4064)
			(stroke
				(width 0.1524)
				(type default)
			)
			(layer "F.SilkS")
		)
		(fp_line
			(start -0.67945 0.3048)
			(end -0.67945 -0.305054)
			(stroke
				(width 0.1)
				(type default)
			)
			(layer "F.Fab")
		)
		(fp_line
			(start -0.12065 0.3048)
			(end -0.67945 0.3048)
			(stroke
				(width 0.1)
				(type default)
			)
			(layer "F.Fab")
		)
		(fp_line
			(start 0.120396 0.3048)
			(end 0.120396 0.2794)
			(stroke
				(width 0.1)
				(type default)
			)
			(layer "F.Fab")
		)
		(fp_line
			(start 0.67945 0.3048)
			(end 0.120396 0.3048)
			(stroke
				(width 0.1)
				(type default)
			)
			(layer "F.Fab")
		)
		(fp_line
			(start -0.12065 0.2794)
			(end -0.12065 0.3048)
			(stroke
				(width 0.1)
				(type default)
			)
			(layer "F.Fab")
		)
		(fp_line
			(start 0.120396 0.2794)
			(end -0.12065 0.2794)
			(stroke
				(width 0.1)
				(type default)
			)
			(layer "F.Fab")
		)
		(fp_line
			(start -0.12065 -0.2794)
			(end 0.12065 -0.2794)
			(stroke
				(width 0.1)
				(type default)
			)
			(layer "F.Fab")
		)
		(fp_line
			(start 0.12065 -0.2794)
			(end 0.12065 -0.3048)
			(stroke
				(width 0.1)
				(type default)
			)
			(layer "F.Fab")
		)
		(fp_line
			(start 0.12065 -0.3048)
			(end 0.67945 -0.3048)
			(stroke
				(width 0.1)
				(type default)
			)
			(layer "F.Fab")
		)
		(fp_line
			(start 0.67945 -0.3048)
			(end 0.67945 0.3048)
			(stroke
				(width 0.1)
				(type default)
			)
			(layer "F.Fab")
		)
		(fp_line
			(start -0.67945 -0.305054)
			(end -0.12065 -0.305054)
			(stroke
				(width 0.1)
				(type default)
			)
			(layer "F.Fab")
		)
		(fp_line
			(start -0.12065 -0.305054)
			(end -0.12065 -0.2794)
			(stroke
				(width 0.1)
				(type default)
			)
			(layer "F.Fab")
		)
		(pad "1" smd circle
			(at -0.40005 0 270)
			(size 0 0)
			(layers "F.Cu" "F.Mask" "F.Paste")
			(net "PVCCIN_CPU1")
		)
		(pad "2" smd circle
			(at 0.40005 0 270)
			(size 0 0)
			(layers "F.Cu" "F.Mask" "F.Paste")
			(net "GND")
		)
	)
	(footprint ""
		(layer "F.Cu")
		(at 123.741942 -16.90751 180)
		(property "Reference" "R4200"
			(at 0 0 180)
			(layer "F.SilkS")
			(hide yes)
			(effects
				(font
					(size 1.27 1.27)
				)
			)
		)
		(property "Value" ""
			(at 0 0 180)
			(layer "F.Fab")
			(effects
				(font
					(size 1.27 1.27)
				)
			)
		)
		(duplicate_pad_numbers_are_jumpers no)
		(fp_line
			(start 0.7874 0.4064)
			(end -0.7874 0.4064)
			(stroke
				(width 0.1524)
				(type default)
			)
			(layer "F.SilkS")
		)
		(fp_line
			(start 0.7874 -0.4064)
			(end 0.7874 0.4064)
			(stroke
				(width 0.1524)
				(type default)
			)
			(layer "F.SilkS")
		)
		(fp_line
			(start -0.7874 0.4064)
			(end -0.7874 -0.4064)
			(stroke
				(width 0.1524)
				(type default)
			)
			(layer "F.SilkS")
		)
		(fp_line
			(start -0.7874 -0.4064)
			(end 0.7874 -0.4064)
			(stroke
				(width 0.1524)
				(type default)
			)
			(layer "F.SilkS")
		)
		(fp_line
			(start 0.67945 0.3048)
			(end 0.120396 0.3048)
			(stroke
				(width 0.1)
				(type default)
			)
			(layer "F.Fab")
		)
		(fp_line
			(start 0.67945 -0.3048)
			(end 0.67945 0.3048)
			(stroke
				(width 0.1)
				(type default)
			)
			(layer "F.Fab")
		)
		(fp_line
			(start 0.12065 -0.2794)
			(end 0.12065 -0.3048)
			(stroke
				(width 0.1)
				(type default)
			)
			(layer "F.Fab")
		)
		(fp_line
			(start 0.12065 -0.3048)
			(end 0.67945 -0.3048)
			(stroke
				(width 0.1)
				(type default)
			)
			(layer "F.Fab")
		)
		(fp_line
			(start 0.120396 0.3048)
			(end 0.120396 0.2794)
			(stroke
				(width 0.1)
				(type default)
			)
			(layer "F.Fab")
		)
		(fp_line
			(start 0.120396 0.2794)
			(end -0.12065 0.2794)
			(stroke
				(width 0.1)
				(type default)
			)
			(layer "F.Fab")
		)
		(fp_line
			(start -0.12065 0.3048)
			(end -0.67945 0.3048)
			(stroke
				(width 0.1)
				(type default)
			)
			(layer "F.Fab")
		)
		(fp_line
			(start -0.12065 0.2794)
			(end -0.12065 0.3048)
			(stroke
				(width 0.1)
				(type default)
			)
			(layer "F.Fab")
		)
		(fp_line
			(start -0.12065 -0.2794)
			(end 0.12065 -0.2794)
			(stroke
				(width 0.1)
				(type default)
			)
			(layer "F.Fab")
		)
		(fp_line
			(start -0.12065 -0.305054)
			(end -0.12065 -0.2794)
			(stroke
				(width 0.1)
				(type default)
			)
			(layer "F.Fab")
		)
		(fp_line
			(start -0.67945 0.3048)
			(end -0.67945 -0.305054)
			(stroke
				(width 0.1)
				(type default)
			)
			(layer "F.Fab")
		)
		(fp_line
			(start -0.67945 -0.305054)
			(end -0.12065 -0.305054)
			(stroke
				(width 0.1)
				(type default)
			)
			(layer "F.Fab")
		)
		(pad "1" smd circle
			(at -0.40005 0 180)
			(size 0 0)
			(layers "F.Cu" "F.Mask" "F.Paste")
			(net "P3V3_AUX")
		)
		(pad "2" smd circle
			(at 0.40005 0 180)
			(size 0 0)
			(layers "F.Cu" "F.Mask" "F.Paste")
			(net "U273_3_ADD0")
		)
	)
)
